# BASEBOARD_FAB2 (Tioga Pass) — schematic netlist excerpt (pin names and nets, part order shuffled) for the footprints in the layout excerpt that follows; sources: Cadence DE-HDL packaged netlist, KiCad conversion of Wiwynn_Tioga_Pass_MB.brd

R9G9  RES  0.0 5% CHIP  pkg 0402  page 141 : A = NIC_SER_P_MDI_3_DP ; B = NIC_MDI_SPRV_RJ45_3_R_DP
FB6P1  FERRITE  600 FB  pkg SMLF  page 102 : A = P3V3 ; B = P3V3_DB1200
C32W4  CAP_A  0.1UF 16V 10% X7R  pkg 0402V  page 185 : A = P3V3_STBY ; B = GND

(kicad_pcb
	(version 20260206)
	(generator "pcbnew")
	(generator_version "10.0")
	(general
		(thickness 1.6)
		(legacy_teardrops no)
	)
	(paper "A4")
	(title_block
		(title "Wiwynn_Tioga_Pass_MB.brd")
		(comment 1 "Tioga Pass / footprints 2831-2833 of 4770")
	)
	(layers
		(0 "F.Cu" signal "TOP")
		(4 "In1.Cu" signal "L2GND")
		(6 "In2.Cu" signal "L3")
		(8 "In3.Cu" signal "L4GND")
		(10 "In4.Cu" signal "L5")
		(12 "In5.Cu" signal "L6GND")
		(14 "In6.Cu" signal "L7VCC")
		(16 "In7.Cu" signal "L8VCC")
		(18 "In8.Cu" signal "L9GND")
		(20 "In9.Cu" signal "L10")
		(22 "In10.Cu" signal "L11GND")
		(24 "In11.Cu" signal "L12")
		(26 "In12.Cu" signal "L13GND")
		(2 "B.Cu" signal "BOTTOM")
		(9 "F.Adhes" user "F.Adhesive")
		(11 "B.Adhes" user "B.Adhesive")
		(13 "F.Paste" user "Package Geometry/Pastemask Top")
		(15 "B.Paste" user "Package Geometry/Pastemask Bottom")
		(5 "F.SilkS" user "Ref Des/Silkscreen Top")
		(7 "B.SilkS" user "Ref Des/Silkscreen Bottom")
		(1 "F.Mask" user "Board Geometry/Soldermask Top")
		(3 "B.Mask" user "Board Geometry/Soldermask Bottom")
		(17 "Dwgs.User" user "User.Drawings")
		(19 "Cmts.User" user "User.Comments")
		(21 "Eco1.User" user "User.Eco1")
		(23 "Eco2.User" user "User.Eco2")
		(25 "Edge.Cuts" user "Board Geometry/Outline")
		(27 "Margin" user)
		(31 "F.CrtYd" user "Package Geometry/Place Bound Top")
		(29 "B.CrtYd" user "Package Geometry/Place Bound Bottom")
		(35 "F.Fab" user "Ref Des/Assembly Top")
		(33 "B.Fab" user "Ref Des/Assembly Bottom")
	)
	(footprint ""
		(layer "B.Cu")
		(at 477.645222 -3.3782 90)
		(property "Reference" "R9G9"
			(at 0 0 90)
			(layer "B.SilkS")
			(hide yes)
			(effects
				(font
					(size 1.27 1.27)
				)
				(justify mirror)
			)
		)
		(property "Value" ""
			(at 0 0 90)
			(layer "B.Fab")
			(effects
				(font
					(size 1.27 1.27)
				)
				(justify mirror)
			)
		)
		(duplicate_pad_numbers_are_jumpers no)
		(fp_poly
			(pts
				(xy 0.2794 -0.1016) (xy -0.2794 -0.1016) (xy -0.2794 0.9906) (xy 0.2794 0.9906)
			)
			(stroke
				(width 0)
				(type default)
			)
			(fill no)
			(layer "B.CrtYd")
		)
		(fp_line
			(start 0.2794 -0.1016)
			(end 0.2794 0.9906)
			(stroke
				(width 0.1)
				(type default)
			)
			(layer "B.Fab")
		)
		(fp_line
			(start -0.2794 -0.1016)
			(end 0.2794 -0.1016)
			(stroke
				(width 0.1)
				(type default)
			)
			(layer "B.Fab")
		)
		(fp_line
			(start 0.2794 0.9906)
			(end -0.2794 0.9906)
			(stroke
				(width 0.1)
				(type default)
			)
			(layer "B.Fab")
		)
		(fp_line
			(start -0.2794 0.9906)
			(end -0.2794 -0.1016)
			(stroke
				(width 0.1)
				(type default)
			)
			(layer "B.Fab")
		)
		(pad "1" smd rect
			(at 0 0 270)
			(size 0.508 0.508)
			(layers "B.Cu" "B.Mask" "B.Paste")
			(net "NIC_SER_P_MDI_3_DP")
		)
		(pad "2" smd rect
			(at 0 0.889 270)
			(size 0.508 0.508)
			(layers "B.Cu" "B.Mask" "B.Paste")
			(net "NIC_MDI_SPRV_RJ45_3_R_DP")
		)
		(zone
			(layer "B.Cu")
			(hatch none 0.5)
			(connect_pads
				(clearance 0)
			)
			(min_thickness 0.25)
			(keepout
				(tracks allowed)
				(vias not_allowed)
				(pads allowed)
				(copperpour not_allowed)
				(footprints allowed)
			)
			(placement
				(enabled no)
				(sheetname "")
			)
			(fill
				(thermal_gap 0.5)
				(thermal_bridge_width 0.5)
				(island_removal_mode 0)
			)
			(polygon
				(pts
					(xy 477.899222 -3.6322) (xy 477.899222 -3.1242) (xy 478.280222 -3.1242) (xy 478.280222 -3.6322)
				)
			)
		)
		(zone
			(layer "B.Cu")
			(hatch none 0.5)
			(connect_pads
				(clearance 0)
			)
			(min_thickness 0.25)
			(keepout
				(tracks not_allowed)
				(vias allowed)
				(pads allowed)
				(copperpour not_allowed)
				(footprints allowed)
			)
			(placement
				(enabled no)
				(sheetname "")
			)
			(fill
				(thermal_gap 0.5)
				(thermal_bridge_width 0.5)
				(island_removal_mode 0)
			)
			(polygon
				(pts
					(xy 478.280222 -3.6322) (xy 478.280222 -3.1242) (xy 477.899222 -3.1242) (xy 477.899222 -3.6322)
				)
			)
		)
	)
	(footprint ""
		(layer "B.Cu")
		(at 176.7078 -79.502 -90)
		(property "Reference" "FB6P1"
			(at 0.53467 4.4958 0)
			(unlocked yes)
			(layer "B.SilkS")
			(effects
				(font
					(size 0.7874 0.5842)
					(thickness 0.1524)
				)
				(justify mirror)
			)
		)
		(property "Value" ""
			(at 0 0 90)
			(layer "B.Fab")
			(effects
				(font
					(size 1.27 1.27)
				)
				(justify mirror)
			)
		)
		(duplicate_pad_numbers_are_jumpers no)
		(fp_poly
			(pts
				(xy 0.7239 -0.26035) (xy -0.7239 -0.26035) (xy -0.7239 2.03835) (xy 0.7239 2.03835)
			)
			(stroke
				(width 0)
				(type default)
			)
			(fill no)
			(layer "B.CrtYd")
		)
		(fp_line
			(start -0.7239 2.03835)
			(end 0.7239 2.03835)
			(stroke
				(width 0.1)
				(type default)
			)
			(layer "B.Fab")
		)
		(fp_line
			(start 0.7239 2.03835)
			(end 0.7239 -0.26035)
			(stroke
				(width 0.1)
				(type default)
			)
			(layer "B.Fab")
		)
		(fp_line
			(start -0.7239 -0.26035)
			(end -0.7239 2.03835)
			(stroke
				(width 0.1)
				(type default)
			)
			(layer "B.Fab")
		)
		(fp_line
			(start 0.7239 -0.26035)
			(end -0.7239 -0.26035)
			(stroke
				(width 0.1)
				(type default)
			)
			(layer "B.Fab")
		)
		(pad "1" smd rect
			(at 0 0 90)
			(size 1.27 1.016)
			(layers "B.Cu" "B.Mask" "B.Paste")
			(net "P3V3")
		)
		(pad "2" smd rect
			(at 0 1.778 90)
			(size 1.27 1.016)
			(layers "B.Cu" "B.Mask" "B.Paste")
			(net "P3V3_DB1200")
		)
		(zone
			(layer "B.Cu")
			(hatch none 0.5)
			(connect_pads
				(clearance 0)
			)
			(min_thickness 0.25)
			(keepout
				(tracks not_allowed)
				(vias allowed)
				(pads allowed)
				(copperpour not_allowed)
				(footprints allowed)
			)
			(placement
				(enabled no)
				(sheetname "")
			)
			(fill
				(thermal_gap 0.5)
				(thermal_bridge_width 0.5)
				(island_removal_mode 0)
			)
			(polygon
				(pts
					(xy 176.1998 -80.137) (xy 175.4378 -80.137) (xy 175.4378 -80.0481) (xy 175.4378 -78.867) (xy 176.1998 -78.867)
				)
			)
		)
	)
	(footprint ""
		(layer "B.Cu")
		(at 390.144 -17.272 -90)
		(property "Reference" "C32W4"
			(at 0.8382 -0.67818 270)
			(unlocked yes)
			(layer "B.SilkS")
			(effects
				(font
					(size 0.4064 0.254)
					(thickness 0.1524)
				)
				(justify left mirror)
			)
		)
		(property "Value" ""
			(at 0 0 90)
			(layer "B.Fab")
			(effects
				(font
					(size 1.27 1.27)
				)
				(justify mirror)
			)
		)
		(duplicate_pad_numbers_are_jumpers no)
		(fp_poly
			(pts
				(xy -0.3048 -0.1016) (xy -0.3048 0.9906) (xy 0.3048 0.9906) (xy 0.3048 -0.1016)
			)
			(stroke
				(width 0)
				(type default)
			)
			(fill no)
			(layer "B.CrtYd")
		)
		(fp_line
			(start -0.3048 0.9906)
			(end -0.3048 -0.1016)
			(stroke
				(width 0.1)
				(type default)
			)
			(layer "B.Fab")
		)
		(fp_line
			(start 0.3048 0.9906)
			(end -0.3048 0.9906)
			(stroke
				(width 0.1)
				(type default)
			)
			(layer "B.Fab")
		)
		(fp_line
			(start -0.3048 -0.1016)
			(end 0.3048 -0.1016)
			(stroke
				(width 0.1)
				(type default)
			)
			(layer "B.Fab")
		)
		(fp_line
			(start 0.3048 -0.1016)
			(end 0.3048 0.9906)
			(stroke
				(width 0.1)
				(type default)
			)
			(layer "B.Fab")
		)
		(pad "1" smd rect
			(at 0 0 90)
			(size 0.508 0.508)
			(layers "B.Cu" "B.Mask" "B.Paste")
			(net "P3V3_STBY")
		)
		(pad "2" smd rect
			(at 0 0.889 90)
			(size 0.508 0.508)
			(layers "B.Cu" "B.Mask" "B.Paste")
			(net "GND")
		)
		(zone
			(layer "B.Cu")
			(hatch none 0.5)
			(connect_pads
				(clearance 0)
			)
			(min_thickness 0.25)
			(keepout
				(tracks not_allowed)
				(vias allowed)
				(pads allowed)
				(copperpour not_allowed)
				(footprints allowed)
			)
			(placement
				(enabled no)
				(sheetname "")
			)
			(fill
				(thermal_gap 0.5)
				(thermal_bridge_width 0.5)
				(island_removal_mode 0)
			)
			(polygon
				(pts
					(xy 389.509 -17.018) (xy 389.509 -17.526) (xy 389.89 -17.526) (xy 389.89 -17.018)
				)
			)
		)
		(zone
			(layer "B.Cu")
			(hatch none 0.5)
			(connect_pads
				(clearance 0)
			)
			(min_thickness 0.25)
			(keepout
				(tracks allowed)
				(vias not_allowed)
				(pads allowed)
				(copperpour not_allowed)
				(footprints allowed)
			)
			(placement
				(enabled no)
				(sheetname "")
			)
			(fill
				(thermal_gap 0.5)
				(thermal_bridge_width 0.5)
				(island_removal_mode 0)
			)
			(polygon
				(pts
					(xy 389.89 -17.018) (xy 389.89 -17.526) (xy 389.509 -17.526) (xy 389.509 -17.018)
				)
			)
		)
	)
)
